(kicad_pcb
	(version 20260206)
	(generator "pcbnew")
	(generator_version "10.0")
	(general
		(thickness 1.6)
		(legacy_teardrops no)
	)
	(paper "A4")
	(title_block
		(title "Bryce Canyon_IOM_IOC_16318-2_OCP.brd")
		(comment 1 "Bryce Canyon / footprints 90-96 of 1605")
	)
	(layers
		(0 "F.Cu" signal "TOP")
		(4 "In1.Cu" signal "L2GND")
		(6 "In2.Cu" signal "L3")
		(8 "In3.Cu" signal "L4VCC")
		(10 "In4.Cu" signal "L5VCC")
		(12 "In5.Cu" signal "L6")
		(14 "In6.Cu" signal "L7GND")
		(2 "B.Cu" signal "BOTTOM")
		(9 "F.Adhes" user "F.Adhesive")
		(11 "B.Adhes" user "B.Adhesive")
		(13 "F.Paste" user "Package Geometry/Pastemask Top")
		(15 "B.Paste" user "Package Geometry/Pastemask Bottom")
		(5 "F.SilkS" user "Ref Des/Silkscreen Top")
		(7 "B.SilkS" user "Ref Des/Silkscreen Bottom")
		(1 "F.Mask" user "Board Geometry/Soldermask Top")
		(3 "B.Mask" user "Board Geometry/Soldermask Bottom")
		(17 "Dwgs.User" user "User.Drawings")
		(19 "Cmts.User" user "User.Comments")
		(21 "Eco1.User" user "User.Eco1")
		(23 "Eco2.User" user "User.Eco2")
		(25 "Edge.Cuts" user "Board Geometry/Outline")
		(27 "Margin" user)
		(31 "F.CrtYd" user "Package Geometry/Place Bound Top")
		(29 "B.CrtYd" user "Package Geometry/Place Bound Bottom")
		(35 "F.Fab" user "Ref Des/Assembly Top")
		(33 "B.Fab" user "Ref Des/Assembly Bottom")
	)
	(footprint ""
		(layer "F.Cu")
		(at 202.0824 -48.2854 180)
		(property "Reference" "R632"
			(at 0 0 180)
			(layer "F.SilkS")
			(hide yes)
			(effects
				(font
					(size 1.27 1.27)
				)
			)
		)
		(property "Value" "4K7R2F-GP"
			(at 0.064008 -3.993896 180)
			(unlocked yes)
			(layer "F.Fab")
			(hide yes)
			(effects
				(font
					(size 1.016 1.016)
					(thickness 0.1524)
				)
			)
		)
		(property "Device Type" "R402H16"
			(at 0.064008 -5.517896 180)
			(unlocked yes)
			(layer "F.Fab")
			(hide yes)
			(effects
				(font
					(size 1.016 1.016)
					(thickness 0.1524)
				)
			)
		)
		(duplicate_pad_numbers_are_jumpers no)
		(fp_line
			(start 0.508 -0.9398)
			(end -0.508 -0.9398)
			(stroke
				(width 0.1524)
				(type default)
			)
			(layer "F.SilkS")
		)
		(fp_line
			(start -0.508 -0.9398)
			(end -0.508 0.9398)
			(stroke
				(width 0.1524)
				(type default)
			)
			(layer "F.SilkS")
		)
		(fp_rect
			(start -0.508 0.9398)
			(end 0.508 -0.9398)
			(stroke
				(width 0)
				(type default)
			)
			(fill no)
			(layer "F.CrtYd")
		)
		(fp_rect
			(start -0.508 0.9398)
			(end 0.508 -0.9398)
			(stroke
				(width 0)
				(type default)
			)
			(fill no)
			(layer "F.Fab")
		)
		(pad "1" smd custom
			(at 0 -0.4445 180)
			(size 0.1397 0.1397)
			(layers "F.Cu" "F.Mask" "F.Paste")
			(net "P1V8")
			(options
				(clearance outline)
				(anchor circle)
			)
			(primitives
				(gr_poly
					(pts
						(arc
							(start -0.1778 -0.2794)
							(mid -0.249642 -0.249642)
							(end -0.2794 -0.1778)
						)
						(arc
							(start -0.2794 0.1778)
							(mid -0.249642 0.249642)
							(end -0.1778 0.2794)
						)
						(arc
							(start 0.1778 0.2794)
							(mid 0.249642 0.249642)
							(end 0.2794 0.1778)
						)
						(arc
							(start 0.2794 -0.1778)
							(mid 0.249642 -0.249642)
							(end 0.1778 -0.2794)
						)
					)
					(width 0)
					(fill yes)
				)
			)
		)
		(pad "2" smd custom
			(at 0 0.4445 180)
			(size 0.1397 0.1397)
			(layers "F.Cu" "F.Mask" "F.Paste")
			(net "ICE1_TCK")
			(options
				(clearance outline)
				(anchor circle)
			)
			(primitives
				(gr_poly
					(pts
						(arc
							(start -0.1778 -0.2794)
							(mid -0.249642 -0.249642)
							(end -0.2794 -0.1778)
						)
						(arc
							(start -0.2794 0.1778)
							(mid -0.249642 0.249642)
							(end -0.1778 0.2794)
						)
						(arc
							(start 0.1778 0.2794)
							(mid 0.249642 0.249642)
							(end 0.2794 0.1778)
						)
						(arc
							(start 0.2794 -0.1778)
							(mid 0.249642 -0.249642)
							(end 0.1778 -0.2794)
						)
					)
					(width 0)
					(fill yes)
				)
			)
		)
	)
	(footprint ""
		(layer "F.Cu")
		(at 35.2044 -134.5438 90)
		(property "Reference" "R280"
			(at 0 0 90)
			(layer "F.SilkS")
			(hide yes)
			(effects
				(font
					(size 1.27 1.27)
				)
			)
		)
		(property "Value" "33R2F-3-GP"
			(at 0.064008 -3.993896 90)
			(unlocked yes)
			(layer "F.Fab")
			(hide yes)
			(effects
				(font
					(size 1.016 1.016)
					(thickness 0.1524)
				)
			)
		)
		(property "Device Type" "R402H16"
			(at 0.064008 -5.517896 90)
			(unlocked yes)
			(layer "F.Fab")
			(hide yes)
			(effects
				(font
					(size 1.016 1.016)
					(thickness 0.1524)
				)
			)
		)
		(duplicate_pad_numbers_are_jumpers no)
		(fp_line
			(start 0.508 -0.9398)
			(end -0.508 -0.9398)
			(stroke
				(width 0.1524)
				(type default)
			)
			(layer "F.SilkS")
		)
		(fp_line
			(start -0.508 -0.9398)
			(end -0.508 0.9398)
			(stroke
				(width 0.1524)
				(type default)
			)
			(layer "F.SilkS")
		)
		(fp_rect
			(start -0.508 0.9398)
			(end 0.508 -0.9398)
			(stroke
				(width 0)
				(type default)
			)
			(fill no)
			(layer "F.CrtYd")
		)
		(fp_rect
			(start -0.508 0.9398)
			(end 0.508 -0.9398)
			(stroke
				(width 0)
				(type default)
			)
			(fill no)
			(layer "F.Fab")
		)
		(pad "1" smd custom
			(at 0 -0.4445 90)
			(size 0.1397 0.1397)
			(layers "F.Cu" "F.Mask" "F.Paste")
			(net "FLA_CS_0_R")
			(options
				(clearance outline)
				(anchor circle)
			)
			(primitives
				(gr_poly
					(pts
						(arc
							(start -0.1778 -0.2794)
							(mid -0.249642 -0.249642)
							(end -0.2794 -0.1778)
						)
						(arc
							(start -0.2794 0.1778)
							(mid -0.249642 0.249642)
							(end -0.1778 0.2794)
						)
						(arc
							(start 0.1778 0.2794)
							(mid 0.249642 0.249642)
							(end 0.2794 0.1778)
						)
						(arc
							(start 0.2794 -0.1778)
							(mid 0.249642 -0.249642)
							(end 0.1778 -0.2794)
						)
					)
					(width 0)
					(fill yes)
				)
			)
		)
		(pad "2" smd custom
			(at 0 0.4445 90)
			(size 0.1397 0.1397)
			(layers "F.Cu" "F.Mask" "F.Paste")
			(net "FLA_CS_0")
			(options
				(clearance outline)
				(anchor circle)
			)
			(primitives
				(gr_poly
					(pts
						(arc
							(start -0.1778 -0.2794)
							(mid -0.249642 -0.249642)
							(end -0.2794 -0.1778)
						)
						(arc
							(start -0.2794 0.1778)
							(mid -0.249642 0.249642)
							(end -0.1778 0.2794)
						)
						(arc
							(start 0.1778 0.2794)
							(mid 0.249642 0.249642)
							(end 0.2794 0.1778)
						)
						(arc
							(start 0.2794 -0.1778)
							(mid 0.249642 -0.249642)
							(end 0.1778 -0.2794)
						)
					)
					(width 0)
					(fill yes)
				)
			)
		)
	)
	(footprint ""
		(layer "F.Cu")
		(at 213.4362 -100.6602 90)
		(property "Reference" "U38"
			(at 0 0 90)
			(layer "F.SilkS")
			(hide yes)
			(effects
				(font
					(size 1.27 1.27)
				)
			)
		)
		(property "Value" "CAT24C64WI-GT3-GP"
			(at -3.707384 -1.5367 90)
			(unlocked yes)
			(layer "F.Fab")
			(hide yes)
			(effects
				(font
					(size 1.016 1.016)
					(thickness 0.1524)
				)
			)
		)
		(property "Device Type" "SOIC8H69"
			(at -3.707384 -3.0607 90)
			(unlocked yes)
			(layer "F.Fab")
			(hide yes)
			(effects
				(font
					(size 1.016 1.016)
					(thickness 0.1524)
				)
			)
		)
		(duplicate_pad_numbers_are_jumpers no)
		(fp_line
			(start 2.1336 -1.4224)
			(end -2.7432 -1.4224)
			(stroke
				(width 0.1524)
				(type default)
			)
			(layer "F.SilkS")
		)
		(fp_line
			(start -2.7432 -1.4224)
			(end -2.7432 1.4224)
			(stroke
				(width 0.1524)
				(type default)
			)
			(layer "F.SilkS")
		)
		(fp_line
			(start -2.7178 -0.508)
			(end -2.1844 -0.0508)
			(stroke
				(width 0.1524)
				(type default)
			)
			(layer "F.SilkS")
		)
		(fp_line
			(start -2.1844 -0.0508)
			(end -2.7178 0.508)
			(stroke
				(width 0.1524)
				(type default)
			)
			(layer "F.SilkS")
		)
		(fp_line
			(start 2.1336 1.4224)
			(end 2.1336 -1.4224)
			(stroke
				(width 0.1524)
				(type default)
			)
			(layer "F.SilkS")
		)
		(fp_line
			(start -2.7432 1.4224)
			(end 2.1336 1.4224)
			(stroke
				(width 0.1524)
				(type default)
			)
			(layer "F.SilkS")
		)
		(fp_line
			(start -2.7432 1.4224)
			(end -2.6416 1.4224)
			(stroke
				(width 0.1524)
				(type default)
			)
			(layer "F.SilkS")
		)
		(fp_line
			(start -2.6289 3.4417)
			(end -2.6289 1.4732)
			(stroke
				(width 0.381)
				(type default)
			)
			(layer "F.SilkS")
		)
		(fp_poly
			(pts
				(xy -2.2098 -1.4224) (xy -2.2098 1.4224) (xy 2.2098 1.4224) (xy 2.2098 -1.4224)
			)
			(stroke
				(width 0)
				(type default)
			)
			(fill yes)
			(layer "F.SilkS")
		)
		(fp_rect
			(start -2.450084 2.999994)
			(end 2.450084 -2.999994)
			(stroke
				(width 0)
				(type default)
			)
			(fill no)
			(layer "F.CrtYd")
		)
		(fp_poly
			(pts
				(xy -2.8194 3.6322) (xy -2.8194 -3.6322) (xy 2.8194 -3.6322) (xy 2.8194 1.18364) (xy 2.450084 1.18364)
				(xy 2.450084 -2.999994) (xy -2.450084 -2.999994) (xy -2.450084 2.999994) (xy 2.450084 2.999994)
				(xy 2.450084 1.18618) (xy 2.8194 1.18618) (xy 2.8194 3.6322)
			)
			(stroke
				(width 0)
				(type default)
			)
			(fill no)
			(layer "F.CrtYd")
		)
		(fp_rect
			(start -2.8194 3.6322)
			(end 2.8194 -3.6322)
			(stroke
				(width 0)
				(type default)
			)
			(fill no)
			(layer "F.Fab")
		)
		(pad "1" smd rect
			(at -1.905 2.54 90)
			(size 0.635 1.651)
			(layers "F.Cu" "F.Mask" "F.Paste")
			(net "IOC_EEPROM_A0")
		)
		(pad "2" smd rect
			(at -0.635 2.54 90)
			(size 0.635 1.651)
			(layers "F.Cu" "F.Mask" "F.Paste")
			(net "IOC_EEPROM_A1")
		)
		(pad "3" smd rect
			(at 0.635 2.54 90)
			(size 0.635 1.651)
			(layers "F.Cu" "F.Mask" "F.Paste")
			(net "IOC_EEPROM_A2")
		)
		(pad "4" smd rect
			(at 1.905 2.54 90)
			(size 0.635 1.651)
			(layers "F.Cu" "F.Mask" "F.Paste")
			(net "GND")
		)
		(pad "5" smd rect
			(at 1.905 -2.54 90)
			(size 0.635 1.651)
			(layers "F.Cu" "F.Mask" "F.Paste")
			(net "IOC_EEPROM_SDA")
		)
		(pad "6" smd rect
			(at 0.635 -2.54 90)
			(size 0.635 1.651)
			(layers "F.Cu" "F.Mask" "F.Paste")
			(net "IOC_EEPROM_SCL")
		)
		(pad "7" smd rect
			(at -0.635 -2.54 90)
			(size 0.635 1.651)
			(layers "F.Cu" "F.Mask" "F.Paste")
			(net "IOC_EEPROM_WP")
		)
		(pad "8" smd rect
			(at -1.905 -2.54 90)
			(size 0.635 1.651)
			(layers "F.Cu" "F.Mask" "F.Paste")
			(net "P1V8")
		)
	)
	(footprint ""
		(layer "F.Cu")
		(at 80.6704 -154.5844)
		(property "Reference" "C239"
			(at 0 0 0)
			(layer "F.SilkS")
			(hide yes)
			(effects
				(font
					(size 1.27 1.27)
				)
			)
		)
		(property "Value" "SCD1U16V2KX-3GP"
			(at 1.1811 -2.7051 0)
			(unlocked yes)
			(layer "F.Fab")
			(hide yes)
			(effects
				(font
					(size 1.016 1.016)
					(thickness 0.1524)
				)
			)
		)
		(property "Device Type" "C402H22"
			(at 1.1811 -4.2291 0)
			(unlocked yes)
			(layer "F.Fab")
			(hide yes)
			(effects
				(font
					(size 1.016 1.016)
					(thickness 0.1524)
				)
			)
		)
		(duplicate_pad_numbers_are_jumpers no)
		(fp_rect
			(start -0.4318 0.9525)
			(end 0.4318 -0.9525)
			(stroke
				(width 0)
				(type default)
			)
			(fill no)
			(layer "F.CrtYd")
		)
		(fp_rect
			(start -0.4318 0.9525)
			(end 0.4318 -0.9525)
			(stroke
				(width 0)
				(type default)
			)
			(fill no)
			(layer "F.Fab")
		)
		(pad "1" smd custom
			(at 0 -0.4445)
			(size 0.1524 0.1524)
			(layers "F.Cu" "F.Mask" "F.Paste")
			(net "TPS74801_P1V15_STBY_OUT")
			(options
				(clearance outline)
				(anchor circle)
			)
			(primitives
				(gr_poly
					(pts
						(arc
							(start 0.3048 -0.2032)
							(mid 0.275042 -0.275042)
							(end 0.2032 -0.3048)
						)
						(arc
							(start -0.2032 -0.3048)
							(mid -0.275042 -0.275042)
							(end -0.3048 -0.2032)
						)
						(arc
							(start -0.3048 0.2032)
							(mid -0.275042 0.275042)
							(end -0.2032 0.3048)
						)
						(arc
							(start 0.2032 0.3048)
							(mid 0.275042 0.275042)
							(end 0.3048 0.2032)
						)
					)
					(width 0)
					(fill yes)
				)
			)
		)
		(pad "2" smd custom
			(at 0 0.4445)
			(size 0.1524 0.1524)
			(layers "F.Cu" "F.Mask" "F.Paste")
			(net "GND")
			(options
				(clearance outline)
				(anchor circle)
			)
			(primitives
				(gr_poly
					(pts
						(arc
							(start 0.3048 -0.2032)
							(mid 0.275042 -0.275042)
							(end 0.2032 -0.3048)
						)
						(arc
							(start -0.2032 -0.3048)
							(mid -0.275042 -0.275042)
							(end -0.3048 -0.2032)
						)
						(arc
							(start -0.3048 0.2032)
							(mid -0.275042 0.275042)
							(end -0.2032 0.3048)
						)
						(arc
							(start 0.2032 0.3048)
							(mid 0.275042 0.275042)
							(end 0.3048 0.2032)
						)
					)
					(width 0)
					(fill yes)
				)
			)
		)
	)
	(footprint ""
		(layer "F.Cu")
		(at 41.68902 -158.8897)
		(property "Reference" "TP186"
			(at 0 0 0)
			(layer "F.SilkS")
			(hide yes)
			(effects
				(font
					(size 1.27 1.27)
				)
			)
		)
		(property "Value" "TPAD28-2-GP"
			(at -0.0127 -1.6637 0)
			(unlocked yes)
			(layer "F.Fab")
			(hide yes)
			(effects
				(font
					(size 1.016 1.016)
					(thickness 0.1524)
				)
			)
		)
		(property "Device Type" "TPAD28"
			(at -0.0127 -3.1877 0)
			(unlocked yes)
			(layer "F.Fab")
			(hide yes)
			(effects
				(font
					(size 1.016 1.016)
					(thickness 0.1524)
				)
			)
		)
		(duplicate_pad_numbers_are_jumpers no)
		(fp_poly
			(pts
				(arc
					(start 0.3556 0)
					(mid -0.3556 0)
					(end 0.3556 0)
				)
			)
			(stroke
				(width 0)
				(type default)
			)
			(fill no)
			(layer "F.CrtYd")
		)
		(fp_poly
			(pts
				(arc
					(start 0.6096 0)
					(mid -0.6096 0)
					(end 0.6096 0)
				)
			)
			(stroke
				(width 0)
				(type default)
			)
			(fill no)
			(layer "F.Fab")
		)
		(pad "1" smd circle
			(at 0 0)
			(size 0.7112 0.7112)
			(layers "F.Cu" "F.Mask" "F.Paste")
			(net "TP_BMC_GPIOL0")
		)
	)
	(footprint ""
		(layer "F.Cu")
		(at 19.15287 -131.007358 180)
		(property "Reference" "R216"
			(at 0 0 180)
			(layer "F.SilkS")
			(hide yes)
			(effects
				(font
					(size 1.27 1.27)
				)
			)
		)
		(property "Value" "120R2F-GP"
			(at 0.064008 -3.993896 180)
			(unlocked yes)
			(layer "F.Fab")
			(hide yes)
			(effects
				(font
					(size 1.016 1.016)
					(thickness 0.1524)
				)
			)
		)
		(property "Device Type" "R402H16"
			(at 0.064008 -5.517896 180)
			(unlocked yes)
			(layer "F.Fab")
			(hide yes)
			(effects
				(font
					(size 1.016 1.016)
					(thickness 0.1524)
				)
			)
		)
		(duplicate_pad_numbers_are_jumpers no)
		(fp_line
			(start 0.508 -0.9398)
			(end -0.508 -0.9398)
			(stroke
				(width 0.1524)
				(type default)
			)
			(layer "F.SilkS")
		)
		(fp_line
			(start -0.508 -0.9398)
			(end -0.508 0.9398)
			(stroke
				(width 0.1524)
				(type default)
			)
			(layer "F.SilkS")
		)
		(fp_rect
			(start -0.508 0.9398)
			(end 0.508 -0.9398)
			(stroke
				(width 0)
				(type default)
			)
			(fill no)
			(layer "F.CrtYd")
		)
		(fp_rect
			(start -0.508 0.9398)
			(end 0.508 -0.9398)
			(stroke
				(width 0)
				(type default)
			)
			(fill no)
			(layer "F.Fab")
		)
		(pad "1" smd custom
			(at 0 -0.4445 180)
			(size 0.1397 0.1397)
			(layers "F.Cu" "F.Mask" "F.Paste")
			(net "MEMCSN")
			(options
				(clearance outline)
				(anchor circle)
			)
			(primitives
				(gr_poly
					(pts
						(arc
							(start -0.1778 -0.2794)
							(mid -0.249642 -0.249642)
							(end -0.2794 -0.1778)
						)
						(arc
							(start -0.2794 0.1778)
							(mid -0.249642 0.249642)
							(end -0.1778 0.2794)
						)
						(arc
							(start 0.1778 0.2794)
							(mid 0.249642 0.249642)
							(end 0.2794 0.1778)
						)
						(arc
							(start 0.2794 -0.1778)
							(mid 0.249642 -0.249642)
							(end 0.1778 -0.2794)
						)
					)
					(width 0)
					(fill yes)
				)
			)
		)
		(pad "2" smd custom
			(at 0 0.4445 180)
			(size 0.1397 0.1397)
			(layers "F.Cu" "F.Mask" "F.Paste")
			(net "P1V2_STBY")
			(options
				(clearance outline)
				(anchor circle)
			)
			(primitives
				(gr_poly
					(pts
						(arc
							(start -0.1778 -0.2794)
							(mid -0.249642 -0.249642)
							(end -0.2794 -0.1778)
						)
						(arc
							(start -0.2794 0.1778)
							(mid -0.249642 0.249642)
							(end -0.1778 0.2794)
						)
						(arc
							(start 0.1778 0.2794)
							(mid 0.249642 0.249642)
							(end 0.2794 0.1778)
						)
						(arc
							(start 0.2794 -0.1778)
							(mid 0.249642 -0.249642)
							(end 0.1778 -0.2794)
						)
					)
					(width 0)
					(fill yes)
				)
			)
		)
	)
	(footprint ""
		(layer "F.Cu")
		(at 193.33972 -30.44444 90)
		(property "Reference" "C526"
			(at 0 0 90)
			(layer "F.SilkS")
			(hide yes)
			(effects
				(font
					(size 1.27 1.27)
				)
			)
		)
		(property "Value" "SC1000P2KV6KX-GP-U"
			(at 0.0508 -3.5052 90)
			(unlocked yes)
			(layer "F.Fab")
			(hide yes)
			(effects
				(font
					(size 1.016 1.016)
					(thickness 0.1524)
				)
			)
		)
		(property "Device Type" "C1206H58"
			(at 0.0508 -5.0292 90)
			(unlocked yes)
			(layer "F.Fab")
			(hide yes)
			(effects
				(font
					(size 1.016 1.016)
					(thickness 0.1524)
				)
			)
		)
		(duplicate_pad_numbers_are_jumpers no)
		(fp_line
			(start 1.016 -2.2352)
			(end -1.016 -2.2352)
			(stroke
				(width 0.1524)
				(type default)
			)
			(layer "F.SilkS")
		)
		(fp_line
			(start 1.016 -2.2352)
			(end 1.016 -0.8382)
			(stroke
				(width 0.1524)
				(type default)
			)
			(layer "F.SilkS")
		)
		(fp_line
			(start -1.016 -2.2352)
			(end -1.016 -0.8382)
			(stroke
				(width 0.1524)
				(type default)
			)
			(layer "F.SilkS")
		)
		(fp_line
			(start 1.016 0.8382)
			(end 1.016 2.2352)
			(stroke
				(width 0.1524)
				(type default)
			)
			(layer "F.SilkS")
		)
		(fp_line
			(start 1.016 2.2352)
			(end -1.016 2.2352)
			(stroke
				(width 0.1524)
				(type default)
			)
			(layer "F.SilkS")
		)
		(fp_line
			(start -1.016 2.2352)
			(end -1.016 0.8128)
			(stroke
				(width 0.1524)
				(type default)
			)
			(layer "F.SilkS")
		)
		(fp_rect
			(start -1.0922 2.3114)
			(end 1.0922 -2.3114)
			(stroke
				(width 0)
				(type default)
			)
			(fill no)
			(layer "F.CrtYd")
		)
		(fp_poly
			(pts
				(xy -1.0922 -2.3114) (xy 1.0922 -2.3114) (xy 1.0922 2.3114) (xy -1.0922 2.3114)
			)
			(stroke
				(width 0)
				(type default)
			)
			(fill no)
			(layer "F.Fab")
		)
		(pad "1" smd rect
			(at 0 -1.397 90)
			(size 1.651 1.27)
			(layers "F.Cu" "F.Mask" "F.Paste")
			(net "EXT1_CONN_GND")
		)
		(pad "2" smd rect
			(at 0 1.397 90)
			(size 1.651 1.27)
			(layers "F.Cu" "F.Mask" "F.Paste")
			(net "GND")
		)
	)
)
